(kicad_pcb
	(version 20260206)
	(generator "pcbnew")
	(generator_version "10.0")
	(general
		(thickness 1.6)
		(legacy_teardrops no)
	)
	(paper "A4")
	(title_block
		(title "Bryce Canyon_R.DPB_16317-1_OCP.brd")
		(comment 1 "Bryce Canyon / footprints 47-50 of 2099")
	)
	(layers
		(0 "F.Cu" signal "TOP")
		(4 "In1.Cu" signal "L2GND")
		(6 "In2.Cu" signal "L3")
		(8 "In3.Cu" signal "L4VCC")
		(10 "In4.Cu" signal "L5VCC")
		(12 "In5.Cu" signal "L6")
		(14 "In6.Cu" signal "L7GND")
		(2 "B.Cu" signal "BOTTOM")
		(9 "F.Adhes" user "F.Adhesive")
		(11 "B.Adhes" user "B.Adhesive")
		(13 "F.Paste" user "Package Geometry/Pastemask Top")
		(15 "B.Paste" user "Package Geometry/Pastemask Bottom")
		(5 "F.SilkS" user "Ref Des/Silkscreen Top")
		(7 "B.SilkS" user "Ref Des/Silkscreen Bottom")
		(1 "F.Mask" user "Board Geometry/Soldermask Top")
		(3 "B.Mask" user "Board Geometry/Soldermask Bottom")
		(17 "Dwgs.User" user "User.Drawings")
		(19 "Cmts.User" user "User.Comments")
		(21 "Eco1.User" user "User.Eco1")
		(23 "Eco2.User" user "User.Eco2")
		(25 "Edge.Cuts" user "Board Geometry/Outline")
		(27 "Margin" user)
		(31 "F.CrtYd" user "Package Geometry/Place Bound Top")
		(29 "B.CrtYd" user "Package Geometry/Place Bound Bottom")
		(35 "F.Fab" user "Ref Des/Assembly Top")
		(33 "B.Fab" user "Ref Des/Assembly Bottom")
	)
	(footprint ""
		(layer "F.Cu")
		(at 473.202 -244.348)
		(property "Reference" "R343"
			(at 0 0 0)
			(layer "F.SilkS")
			(hide yes)
			(effects
				(font
					(size 1.27 1.27)
				)
			)
		)
		(property "Value" "4K7R2F-GP"
			(at 0.064008 -3.993896 0)
			(unlocked yes)
			(layer "F.Fab")
			(hide yes)
			(effects
				(font
					(size 1.016 1.016)
					(thickness 0.1524)
				)
			)
		)
		(property "Device Type" "R402H16"
			(at 0.064008 -5.517896 0)
			(unlocked yes)
			(layer "F.Fab")
			(hide yes)
			(effects
				(font
					(size 1.016 1.016)
					(thickness 0.1524)
				)
			)
		)
		(duplicate_pad_numbers_are_jumpers no)
		(fp_line
			(start -0.508 -0.9398)
			(end -0.508 0.9398)
			(stroke
				(width 0.1524)
				(type default)
			)
			(layer "F.SilkS")
		)
		(fp_line
			(start 0.508 -0.9398)
			(end -0.508 -0.9398)
			(stroke
				(width 0.1524)
				(type default)
			)
			(layer "F.SilkS")
		)
		(fp_rect
			(start -0.508 0.9398)
			(end 0.508 -0.9398)
			(stroke
				(width 0)
				(type default)
			)
			(fill no)
			(layer "F.CrtYd")
		)
		(fp_rect
			(start -0.508 0.9398)
			(end 0.508 -0.9398)
			(stroke
				(width 0)
				(type default)
			)
			(fill no)
			(layer "F.Fab")
		)
		(pad "1" smd custom
			(at 0 -0.4445)
			(size 0.1397 0.1397)
			(layers "F.Cu" "F.Mask" "F.Paste")
			(net "SW_PWR_R_HDD11")
			(options
				(clearance outline)
				(anchor circle)
			)
			(primitives
				(gr_poly
					(pts
						(arc
							(start -0.1778 -0.2794)
							(mid -0.249642 -0.249642)
							(end -0.2794 -0.1778)
						)
						(arc
							(start -0.2794 0.1778)
							(mid -0.249642 0.249642)
							(end -0.1778 0.2794)
						)
						(arc
							(start 0.1778 0.2794)
							(mid 0.249642 0.249642)
							(end 0.2794 0.1778)
						)
						(arc
							(start 0.2794 -0.1778)
							(mid 0.249642 -0.249642)
							(end 0.1778 -0.2794)
						)
					)
					(width 0)
					(fill yes)
				)
			)
		)
		(pad "2" smd custom
			(at 0 0.4445)
			(size 0.1397 0.1397)
			(layers "F.Cu" "F.Mask" "F.Paste")
			(net "GND")
			(options
				(clearance outline)
				(anchor circle)
			)
			(primitives
				(gr_poly
					(pts
						(arc
							(start -0.1778 -0.2794)
							(mid -0.249642 -0.249642)
							(end -0.2794 -0.1778)
						)
						(arc
							(start -0.2794 0.1778)
							(mid -0.249642 0.249642)
							(end -0.1778 0.2794)
						)
						(arc
							(start 0.1778 0.2794)
							(mid 0.249642 0.249642)
							(end 0.2794 0.1778)
						)
						(arc
							(start 0.2794 -0.1778)
							(mid 0.249642 -0.249642)
							(end 0.1778 -0.2794)
						)
					)
					(width 0)
					(fill yes)
				)
			)
		)
	)
	(footprint ""
		(layer "F.Cu")
		(at 77.978 -30.861)
		(property "Reference" "Q132"
			(at 0 0 0)
			(layer "F.SilkS")
			(hide yes)
			(effects
				(font
					(size 1.27 1.27)
				)
			)
		)
		(property "Value" "AO4407AL-GP"
			(at -3.707384 -1.5367 0)
			(unlocked yes)
			(layer "F.Fab")
			(hide yes)
			(effects
				(font
					(size 1.016 1.016)
					(thickness 0.1524)
				)
			)
		)
		(property "Device Type" "SOIC8H69"
			(at -3.707384 -3.0607 0)
			(unlocked yes)
			(layer "F.Fab")
			(hide yes)
			(effects
				(font
					(size 1.016 1.016)
					(thickness 0.1524)
				)
			)
		)
		(duplicate_pad_numbers_are_jumpers no)
		(fp_line
			(start -2.7432 -1.4224)
			(end -2.7432 1.4224)
			(stroke
				(width 0.1524)
				(type default)
			)
			(layer "F.SilkS")
		)
		(fp_line
			(start -2.7432 1.4224)
			(end -2.6416 1.4224)
			(stroke
				(width 0.1524)
				(type default)
			)
			(layer "F.SilkS")
		)
		(fp_line
			(start -2.7432 1.4224)
			(end 2.1336 1.4224)
			(stroke
				(width 0.1524)
				(type default)
			)
			(layer "F.SilkS")
		)
		(fp_line
			(start -2.7178 -0.508)
			(end -2.1844 -0.0508)
			(stroke
				(width 0.1524)
				(type default)
			)
			(layer "F.SilkS")
		)
		(fp_line
			(start -2.6289 3.4417)
			(end -2.6289 1.4732)
			(stroke
				(width 0.381)
				(type default)
			)
			(layer "F.SilkS")
		)
		(fp_line
			(start -2.1844 -0.0508)
			(end -2.7178 0.508)
			(stroke
				(width 0.1524)
				(type default)
			)
			(layer "F.SilkS")
		)
		(fp_line
			(start 2.1336 -1.4224)
			(end -2.7432 -1.4224)
			(stroke
				(width 0.1524)
				(type default)
			)
			(layer "F.SilkS")
		)
		(fp_line
			(start 2.1336 1.4224)
			(end 2.1336 -1.4224)
			(stroke
				(width 0.1524)
				(type default)
			)
			(layer "F.SilkS")
		)
		(fp_poly
			(pts
				(xy -2.2098 -1.4224) (xy -2.2098 1.4224) (xy 2.2098 1.4224) (xy 2.2098 -1.4224)
			)
			(stroke
				(width 0)
				(type default)
			)
			(fill yes)
			(layer "F.SilkS")
		)
		(fp_rect
			(start -2.450084 2.999994)
			(end 2.450084 -2.999994)
			(stroke
				(width 0)
				(type default)
			)
			(fill no)
			(layer "F.CrtYd")
		)
		(fp_poly
			(pts
				(xy -2.8194 3.6322) (xy -2.8194 -3.6322) (xy 2.8194 -3.6322) (xy 2.8194 1.18364) (xy 2.450084 1.18364)
				(xy 2.450084 -2.999994) (xy -2.450084 -2.999994) (xy -2.450084 2.999994) (xy 2.450084 2.999994)
				(xy 2.450084 1.18618) (xy 2.8194 1.18618) (xy 2.8194 3.6322)
			)
			(stroke
				(width 0)
				(type default)
			)
			(fill no)
			(layer "F.CrtYd")
		)
		(fp_rect
			(start -2.8194 3.6322)
			(end 2.8194 -3.6322)
			(stroke
				(width 0)
				(type default)
			)
			(fill no)
			(layer "F.Fab")
		)
		(pad "1" smd rect
			(at -1.905 2.54)
			(size 0.635 1.651)
			(layers "F.Cu" "F.Mask" "F.Paste")
			(net "P12V_B")
		)
		(pad "2" smd rect
			(at -0.635 2.54)
			(size 0.635 1.651)
			(layers "F.Cu" "F.Mask" "F.Paste")
			(net "P12V_B")
		)
		(pad "3" smd rect
			(at 0.635 2.54)
			(size 0.635 1.651)
			(layers "F.Cu" "F.Mask" "F.Paste")
			(net "P12V_B")
		)
		(pad "4" smd rect
			(at 1.905 2.54)
			(size 0.635 1.651)
			(layers "F.Cu" "F.Mask" "F.Paste")
			(net "SW_HDD_N26")
		)
		(pad "5" smd rect
			(at 1.905 -2.54)
			(size 0.635 1.651)
			(layers "F.Cu" "F.Mask" "F.Paste")
			(net "P12V_HDD26")
		)
		(pad "6" smd rect
			(at 0.635 -2.54)
			(size 0.635 1.651)
			(layers "F.Cu" "F.Mask" "F.Paste")
			(net "P12V_HDD26")
		)
		(pad "7" smd rect
			(at -0.635 -2.54)
			(size 0.635 1.651)
			(layers "F.Cu" "F.Mask" "F.Paste")
			(net "P12V_HDD26")
		)
		(pad "8" smd rect
			(at -1.905 -2.54)
			(size 0.635 1.651)
			(layers "F.Cu" "F.Mask" "F.Paste")
			(net "P12V_HDD26")
		)
	)
	(footprint ""
		(layer "F.Cu")
		(at 190.213488 -14.660626 90)
		(property "Reference" "C406"
			(at 0 0 90)
			(layer "F.SilkS")
			(hide yes)
			(effects
				(font
					(size 1.27 1.27)
				)
			)
		)
		(property "Value" "SCD01U16V1KX-GP"
			(at -2.8321 -1.7399 90)
			(unlocked yes)
			(layer "F.Fab")
			(hide yes)
			(effects
				(font
					(size 1.016 1.016)
					(thickness 0.1524)
				)
			)
		)
		(property "Device Type" "C0201H13"
			(at -2.8321 -3.2639 90)
			(unlocked yes)
			(layer "F.Fab")
			(hide yes)
			(effects
				(font
					(size 1.016 1.016)
					(thickness 0.1524)
				)
			)
		)
		(duplicate_pad_numbers_are_jumpers no)
		(fp_rect
			(start -0.2794 0.6477)
			(end 0.2794 -0.6477)
			(stroke
				(width 0)
				(type default)
			)
			(fill no)
			(layer "F.CrtYd")
		)
		(fp_rect
			(start -0.2794 0.6477)
			(end 0.2794 -0.6477)
			(stroke
				(width 0)
				(type default)
			)
			(fill no)
			(layer "F.Fab")
		)
		(pad "1" smd custom
			(at 0 -0.2794 90)
			(size 0.0762 0.0762)
			(layers "F.Cu" "F.Mask" "F.Paste")
			(net "SAS_HDD_RX_P29")
			(options
				(clearance outline)
				(anchor circle)
			)
			(primitives
				(gr_poly
					(pts
						(arc
							(start 0.1524 -0.127)
							(mid 0.137521 -0.162921)
							(end 0.1016 -0.1778)
						)
						(arc
							(start -0.1016 -0.1778)
							(mid -0.137521 -0.162921)
							(end -0.1524 -0.127)
						)
						(arc
							(start -0.1524 0.127)
							(mid -0.137521 0.162921)
							(end -0.1016 0.1778)
						)
						(arc
							(start 0.1016 0.1778)
							(mid 0.137521 0.162921)
							(end 0.1524 0.127)
						)
					)
					(width 0)
					(fill yes)
				)
			)
		)
		(pad "2" smd custom
			(at 0 0.2794 90)
			(size 0.0762 0.0762)
			(layers "F.Cu" "F.Mask" "F.Paste")
			(net "PHY_SCC_B_TO_DRV_B_29_DP")
			(options
				(clearance outline)
				(anchor circle)
			)
			(primitives
				(gr_poly
					(pts
						(arc
							(start 0.1524 -0.127)
							(mid 0.137521 -0.162921)
							(end 0.1016 -0.1778)
						)
						(arc
							(start -0.1016 -0.1778)
							(mid -0.137521 -0.162921)
							(end -0.1524 -0.127)
						)
						(arc
							(start -0.1524 0.127)
							(mid -0.137521 0.162921)
							(end -0.1016 0.1778)
						)
						(arc
							(start 0.1016 0.1778)
							(mid 0.137521 0.162921)
							(end 0.1524 0.127)
						)
					)
					(width 0)
					(fill yes)
				)
			)
		)
	)
	(footprint ""
		(layer "F.Cu")
		(at 286.086804 -287.690052 -90)
		(property "Reference" "PWR1"
			(at 0 0 270)
			(layer "F.SilkS")
			(hide yes)
			(effects
				(font
					(size 1.27 1.27)
				)
			)
		)
		(property "Value" "AMP-CONN8-2R-2-GP"
			(at 15.875 6.604 270)
			(unlocked yes)
			(layer "F.Fab")
			(hide yes)
			(effects
				(font
					(size 1.016 1.016)
					(thickness 0.1524)
				)
			)
		)
		(property "Device Type" "PREFIT-8P-5697-1H404"
			(at 15.875 5.08 270)
			(unlocked yes)
			(layer "F.Fab")
			(hide yes)
			(effects
				(font
					(size 1.016 1.016)
					(thickness 0.1524)
				)
			)
		)
		(duplicate_pad_numbers_are_jumpers no)
		(fp_line
			(start -1.4478 8.2804)
			(end -1.4478 -1.9558)
			(stroke
				(width 0.1524)
				(type default)
			)
			(layer "F.SilkS")
		)
		(fp_line
			(start 4.6482 8.2804)
			(end -1.4478 8.2804)
			(stroke
				(width 0.1524)
				(type default)
			)
			(layer "F.SilkS")
		)
		(fp_line
			(start -1.4478 -1.9558)
			(end 4.6482 -1.9558)
			(stroke
				(width 0.1524)
				(type default)
			)
			(layer "F.SilkS")
		)
		(fp_line
			(start 4.6482 -1.9558)
			(end 4.6482 8.2804)
			(stroke
				(width 0.1524)
				(type default)
			)
			(layer "F.SilkS")
		)
		(fp_poly
			(pts
				(xy -1.4478 8.2804) (xy -1.4478 -0.864616) (xy -0.8636 -0.864616) (xy -0.8636 8.128) (xy 4.063492 8.128)
				(xy 4.063492 -0.864616) (xy 4.6482 -0.864616) (xy 4.6482 8.2804)
			)
			(stroke
				(width 0)
				(type default)
			)
			(fill yes)
			(layer "F.SilkS")
		)
		(fp_poly
			(pts
				(arc
					(start 0.2032 7.8486)
					(mid 0 8.0518)
					(end -0.2032 7.8486)
				)
				(arc
					(start -0.2032 7.6454)
					(mid 0 7.4422)
					(end 0.2032 7.6454)
				)
			)
			(stroke
				(width 0)
				(type default)
			)
			(fill yes)
			(layer "F.SilkS")
		)
		(fp_poly
			(pts
				(arc
					(start 3.403092 7.8486)
					(mid 3.199892 8.0518)
					(end 2.996692 7.8486)
				)
				(arc
					(start 2.996692 7.6454)
					(mid 3.199892 7.4422)
					(end 3.403092 7.6454)
				)
			)
			(stroke
				(width 0)
				(type default)
			)
			(fill yes)
			(layer "F.SilkS")
		)
		(fp_rect
			(start -5.6134 11.938)
			(end 8.8138 -5.6134)
			(stroke
				(width 0)
				(type default)
			)
			(fill no)
			(layer "B.CrtYd")
		)
		(fp_rect
			(start -1.1938 8.0264)
			(end 4.3942 -1.7018)
			(stroke
				(width 0)
				(type default)
			)
			(fill no)
			(layer "F.CrtYd")
		)
		(fp_poly
			(pts
				(xy -6.1976 13.0302) (xy -6.1976 -6.7056) (xy 9.398 -6.7056) (xy 9.398 0) (xy 4.9022 0) (xy 4.9022 -2.2098)
				(xy -1.7018 -2.2098) (xy -1.7018 8.5344) (xy 4.9022 8.5344) (xy 4.9022 0.0127) (xy 9.398 0.0127)
				(xy 9.398 13.0302)
			)
			(stroke
				(width 0)
				(type default)
			)
			(fill no)
			(layer "F.CrtYd")
		)
		(fp_poly
			(pts
				(xy -1.7018 8.5344) (xy -1.7018 -2.2098) (xy 4.9022 -2.2098) (xy 4.9022 0) (xy 4.3942 0) (xy 4.3942 -1.7018)
				(xy -1.1938 -1.7018) (xy -1.1938 8.0264) (xy 4.3942 8.0264) (xy 4.3942 0.0127) (xy 4.9022 0.0127)
				(xy 4.9022 8.5344)
			)
			(stroke
				(width 0)
				(type default)
			)
			(fill no)
			(layer "F.CrtYd")
		)
		(fp_rect
			(start -10.6172 16.9418)
			(end 13.8176 -10.6172)
			(stroke
				(width 0)
				(type default)
			)
			(fill no)
			(layer "B.Fab")
		)
		(fp_rect
			(start -5.6134 11.938)
			(end 8.8138 -5.6134)
			(stroke
				(width 0)
				(type default)
			)
			(fill no)
			(layer "B.Fab")
		)
		(fp_rect
			(start -11.2014 18.034)
			(end 14.4018 -11.7094)
			(stroke
				(width 0)
				(type default)
			)
			(fill no)
			(layer "F.Fab")
		)
		(fp_rect
			(start -6.1976 13.0302)
			(end 9.398 -6.7056)
			(stroke
				(width 0)
				(type default)
			)
			(fill no)
			(layer "F.Fab")
		)
		(fp_rect
			(start -1.7018 8.5344)
			(end 4.9022 -2.2098)
			(stroke
				(width 0)
				(type default)
			)
			(fill no)
			(layer "F.Fab")
		)
		(fp_text user "Pre Fit"
			(at -2.286 -1.3462 270)
			(unlocked yes)
			(layer "F.SilkS")
			(effects
				(font
					(size 1.016 1.016)
					(thickness 0.1524)
				)
				(justify left)
			)
		)
		(fp_text user "Can not place BGA,CSP,Wave Solder Component"
			(at -24.9428 14.9352 270)
			(unlocked yes)
			(layer "B.Fab")
			(effects
				(font
					(size 1.016 1.016)
					(thickness 0.1524)
				)
				(justify left)
			)
		)
		(fp_text user "Can not place BGA,CSP,Wave Solder Component"
			(at -22.987 15.9258 270)
			(unlocked yes)
			(layer "F.Fab")
			(effects
				(font
					(size 1.016 1.016)
					(thickness 0.1524)
				)
				(justify left)
			)
		)
		(fp_text user "High Limit 2mm"
			(at -6.604 11.3538 270)
			(unlocked yes)
			(layer "F.Fab")
			(effects
				(font
					(size 1.016 1.016)
					(thickness 0.1524)
				)
				(justify left)
			)
		)
		(pad "A1" thru_hole oval
			(at 0 0 270)
			(size 1.2192 2.921)
			(drill 0.739902
				(offset 0 0.849884)
			)
			(layers "*.Cu" "*.Mask")
			(remove_unused_layers no)
			(net "P12V_B")
			(clearance 0.127)
			(thermal_gap 0.127)
			(padstack
				(mode front_inner_back)
				(layer "Inner"
					(shape circle)
					(size 1.2192 1.2192)
					(clearance 0.127)
				)
				(layer "B.Cu"
					(shape circle)
					(size 1.2192 1.2192)
					(clearance 0.127)
				)
			)
		)
		(pad "A2" thru_hole circle
			(at 0 1.700022 270)
			(size 1.2192 1.2192)
			(drill 0.739902)
			(layers "*.Cu" "*.Mask")
			(remove_unused_layers no)
			(net "P12V_B")
			(clearance 0.127)
			(thermal_gap 0.127)
		)
		(pad "A3" thru_hole oval
			(at 0 4.629912 270)
			(size 1.2192 2.921)
			(drill 0.739902
				(offset 0 0.849884)
			)
			(layers "*.Cu" "*.Mask")
			(remove_unused_layers no)
			(net "P12V_B")
			(clearance 0.127)
			(thermal_gap 0.127)
			(padstack
				(mode front_inner_back)
				(layer "Inner"
					(shape circle)
					(size 1.2192 1.2192)
					(clearance 0.127)
				)
				(layer "B.Cu"
					(shape circle)
					(size 1.2192 1.2192)
					(clearance 0.127)
				)
			)
		)
		(pad "A4" thru_hole circle
			(at 0 6.329934 270)
			(size 1.2192 1.2192)
			(drill 0.739902)
			(layers "*.Cu" "*.Mask")
			(remove_unused_layers no)
			(net "P12V_B")
			(clearance 0.127)
			(thermal_gap 0.127)
		)
		(pad "B1" thru_hole oval
			(at 3.199892 0 270)
			(size 1.2192 2.921)
			(drill 0.739902
				(offset 0 0.849884)
			)
			(layers "*.Cu" "*.Mask")
			(remove_unused_layers no)
			(net "GND")
			(clearance 0.127)
			(thermal_gap 0.127)
			(padstack
				(mode front_inner_back)
				(layer "Inner"
					(shape circle)
					(size 1.2192 1.2192)
					(clearance 0.127)
				)
				(layer "B.Cu"
					(shape circle)
					(size 1.2192 1.2192)
					(clearance 0.127)
				)
			)
		)
		(pad "B2" thru_hole circle
			(at 3.199892 1.700022 270)
			(size 1.2192 1.2192)
			(drill 0.739902)
			(layers "*.Cu" "*.Mask")
			(remove_unused_layers no)
			(net "GND")
			(clearance 0.127)
			(thermal_gap 0.127)
		)
		(pad "B3" thru_hole oval
			(at 3.199892 4.629912 270)
			(size 1.2192 2.921)
			(drill 0.739902
				(offset 0 0.849884)
			)
			(layers "*.Cu" "*.Mask")
			(remove_unused_layers no)
			(net "GND")
			(clearance 0.127)
			(thermal_gap 0.127)
			(padstack
				(mode front_inner_back)
				(layer "Inner"
					(shape circle)
					(size 1.2192 1.2192)
					(clearance 0.127)
				)
				(layer "B.Cu"
					(shape circle)
					(size 1.2192 1.2192)
					(clearance 0.127)
				)
			)
		)
		(pad "B4" thru_hole circle
			(at 3.199892 6.329934 270)
			(size 1.2192 1.2192)
			(drill 0.739902)
			(layers "*.Cu" "*.Mask")
			(remove_unused_layers no)
			(net "GND")
			(clearance 0.127)
			(thermal_gap 0.127)
		)
		(zone
			(layer "F.Cu")
			(hatch none 0.5)
			(connect_pads
				(clearance 0)
			)
			(min_thickness 0.25)
			(keepout
				(tracks allowed)
				(vias not_allowed)
				(pads allowed)
				(copperpour not_allowed)
				(footprints allowed)
			)
			(placement
				(enabled no)
				(sheetname "")
			)
			(fill
				(thermal_gap 0.5)
				(thermal_bridge_width 0.5)
				(island_removal_mode 0)
			)
			(polygon
				(pts
					(xy 278.906732 -288.539936) (xy 278.906732 -283.640022) (xy 286.936688 -283.640022) (xy 286.936688 -288.539936)
				)
			)
		)
		(zone
			(layer "F.Cu")
			(hatch none 0.5)
			(connect_pads
				(clearance 0)
			)
			(min_thickness 0.25)
			(keepout
				(tracks not_allowed)
				(vias allowed)
				(pads allowed)
				(copperpour not_allowed)
				(footprints allowed)
			)
			(placement
				(enabled no)
				(sheetname "")
			)
			(fill
				(thermal_gap 0.5)
				(thermal_bridge_width 0.5)
				(island_removal_mode 0)
			)
			(polygon
				(pts
					(xy 278.906732 -288.539936) (xy 278.906732 -283.640022) (xy 286.936688 -283.640022) (xy 286.936688 -288.539936)
				)
			)
		)
	)
)
